(kicad_pcb
	(version 20260206)
	(generator "pcbnew")
	(generator_version "10.0")
	(general
		(thickness 1.6)
		(legacy_teardrops no)
	)
	(paper "A4")
	(title_block
		(title "12092022_DA0F0TFB6D0_F0T_FAN_BOARD_MP5048_D_brd_v02_OCP.brd")
		(comment 1 "Grand Teton / footprints 677-683 of 924")
	)
	(layers
		(0 "F.Cu" signal "TOP")
		(4 "In1.Cu" signal "GND")
		(6 "In2.Cu" signal "IN1")
		(8 "In3.Cu" signal "IN2")
		(10 "In4.Cu" signal "GND1")
		(2 "B.Cu" signal "BOTTOM")
		(9 "F.Adhes" user "F.Adhesive")
		(11 "B.Adhes" user "B.Adhesive")
		(13 "F.Paste" user "Package Geometry/Pastemask Top")
		(15 "B.Paste" user "Package Geometry/Pastemask Bottom")
		(5 "F.SilkS" user "Ref Des/Silkscreen Top")
		(7 "B.SilkS" user "Ref Des/Silkscreen Bottom")
		(1 "F.Mask" user "Board Geometry/Soldermask Top")
		(3 "B.Mask" user "Board Geometry/Soldermask Bottom")
		(17 "Dwgs.User" user "User.Drawings")
		(19 "Cmts.User" user "User.Comments")
		(21 "Eco1.User" user "User.Eco1")
		(23 "Eco2.User" user "User.Eco2")
		(25 "Edge.Cuts" user "Board Geometry/Outline")
		(27 "Margin" user)
		(31 "F.CrtYd" user "Package Geometry/Place Bound Top")
		(29 "B.CrtYd" user "Package Geometry/Place Bound Bottom")
		(35 "F.Fab" user "Ref Des/Assembly Top")
		(33 "B.Fab" user "Ref Des/Assembly Bottom")
	)
	(footprint ""
		(layer "F.Cu")
		(at 16.891 -112.649 180)
		(property "Reference" "R5537"
			(at 0 0 180)
			(layer "F.SilkS")
			(hide yes)
			(effects
				(font
					(size 1.27 1.27)
				)
			)
		)
		(property "Value" ""
			(at 0 0 180)
			(layer "F.Fab")
			(effects
				(font
					(size 1.27 1.27)
				)
			)
		)
		(duplicate_pad_numbers_are_jumpers no)
		(fp_line
			(start 0.7874 0.4064)
			(end -0.7874 0.4064)
			(stroke
				(width 0.1524)
				(type default)
			)
			(layer "F.SilkS")
		)
		(fp_line
			(start 0.7874 -0.4064)
			(end 0.7874 0.4064)
			(stroke
				(width 0.1524)
				(type default)
			)
			(layer "F.SilkS")
		)
		(fp_line
			(start -0.7874 0.4064)
			(end -0.7874 -0.4064)
			(stroke
				(width 0.1524)
				(type default)
			)
			(layer "F.SilkS")
		)
		(fp_line
			(start -0.7874 -0.4064)
			(end 0.7874 -0.4064)
			(stroke
				(width 0.1524)
				(type default)
			)
			(layer "F.SilkS")
		)
		(fp_line
			(start 0.67945 0.3048)
			(end 0.120396 0.3048)
			(stroke
				(width 0.1)
				(type default)
			)
			(layer "F.Fab")
		)
		(fp_line
			(start 0.67945 -0.3048)
			(end 0.67945 0.3048)
			(stroke
				(width 0.1)
				(type default)
			)
			(layer "F.Fab")
		)
		(fp_line
			(start 0.12065 -0.2794)
			(end 0.12065 -0.3048)
			(stroke
				(width 0.1)
				(type default)
			)
			(layer "F.Fab")
		)
		(fp_line
			(start 0.12065 -0.3048)
			(end 0.67945 -0.3048)
			(stroke
				(width 0.1)
				(type default)
			)
			(layer "F.Fab")
		)
		(fp_line
			(start 0.120396 0.3048)
			(end 0.120396 0.2794)
			(stroke
				(width 0.1)
				(type default)
			)
			(layer "F.Fab")
		)
		(fp_line
			(start 0.120396 0.2794)
			(end -0.12065 0.2794)
			(stroke
				(width 0.1)
				(type default)
			)
			(layer "F.Fab")
		)
		(fp_line
			(start -0.12065 0.3048)
			(end -0.67945 0.3048)
			(stroke
				(width 0.1)
				(type default)
			)
			(layer "F.Fab")
		)
		(fp_line
			(start -0.12065 0.2794)
			(end -0.12065 0.3048)
			(stroke
				(width 0.1)
				(type default)
			)
			(layer "F.Fab")
		)
		(fp_line
			(start -0.12065 -0.2794)
			(end 0.12065 -0.2794)
			(stroke
				(width 0.1)
				(type default)
			)
			(layer "F.Fab")
		)
		(fp_line
			(start -0.12065 -0.305054)
			(end -0.12065 -0.2794)
			(stroke
				(width 0.1)
				(type default)
			)
			(layer "F.Fab")
		)
		(fp_line
			(start -0.67945 0.3048)
			(end -0.67945 -0.305054)
			(stroke
				(width 0.1)
				(type default)
			)
			(layer "F.Fab")
		)
		(fp_line
			(start -0.67945 -0.305054)
			(end -0.12065 -0.305054)
			(stroke
				(width 0.1)
				(type default)
			)
			(layer "F.Fab")
		)
		(pad "1" smd rect
			(at -0.40005 0)
			(size 0.4572 0.508)
			(layers "F.Cu" "F.Mask" "F.Paste")
			(net "P12V_LED_FAN5")
		)
		(pad "2" smd rect
			(at 0.40005 0)
			(size 0.4572 0.508)
			(layers "F.Cu" "F.Mask" "F.Paste")
			(net "FAN_5_OK_LED_R_N")
		)
	)
	(footprint ""
		(layer "F.Cu")
		(at 37.211 -202.311)
		(property "Reference" "R5412"
			(at 0 0 0)
			(layer "F.SilkS")
			(hide yes)
			(effects
				(font
					(size 1.27 1.27)
				)
			)
		)
		(property "Value" ""
			(at 0 0 0)
			(layer "F.Fab")
			(effects
				(font
					(size 1.27 1.27)
				)
			)
		)
		(duplicate_pad_numbers_are_jumpers no)
		(fp_line
			(start -0.7874 -0.4064)
			(end 0.7874 -0.4064)
			(stroke
				(width 0.1524)
				(type default)
			)
			(layer "F.SilkS")
		)
		(fp_line
			(start -0.7874 0.4064)
			(end -0.7874 -0.4064)
			(stroke
				(width 0.1524)
				(type default)
			)
			(layer "F.SilkS")
		)
		(fp_line
			(start 0.7874 -0.4064)
			(end 0.7874 0.4064)
			(stroke
				(width 0.1524)
				(type default)
			)
			(layer "F.SilkS")
		)
		(fp_line
			(start 0.7874 0.4064)
			(end -0.7874 0.4064)
			(stroke
				(width 0.1524)
				(type default)
			)
			(layer "F.SilkS")
		)
		(fp_line
			(start -0.67945 -0.305054)
			(end -0.12065 -0.305054)
			(stroke
				(width 0.1)
				(type default)
			)
			(layer "F.Fab")
		)
		(fp_line
			(start -0.67945 0.3048)
			(end -0.67945 -0.305054)
			(stroke
				(width 0.1)
				(type default)
			)
			(layer "F.Fab")
		)
		(fp_line
			(start -0.12065 -0.305054)
			(end -0.12065 -0.2794)
			(stroke
				(width 0.1)
				(type default)
			)
			(layer "F.Fab")
		)
		(fp_line
			(start -0.12065 -0.2794)
			(end 0.12065 -0.2794)
			(stroke
				(width 0.1)
				(type default)
			)
			(layer "F.Fab")
		)
		(fp_line
			(start -0.12065 0.2794)
			(end -0.12065 0.3048)
			(stroke
				(width 0.1)
				(type default)
			)
			(layer "F.Fab")
		)
		(fp_line
			(start -0.12065 0.3048)
			(end -0.67945 0.3048)
			(stroke
				(width 0.1)
				(type default)
			)
			(layer "F.Fab")
		)
		(fp_line
			(start 0.120396 0.2794)
			(end -0.12065 0.2794)
			(stroke
				(width 0.1)
				(type default)
			)
			(layer "F.Fab")
		)
		(fp_line
			(start 0.120396 0.3048)
			(end 0.120396 0.2794)
			(stroke
				(width 0.1)
				(type default)
			)
			(layer "F.Fab")
		)
		(fp_line
			(start 0.12065 -0.3048)
			(end 0.67945 -0.3048)
			(stroke
				(width 0.1)
				(type default)
			)
			(layer "F.Fab")
		)
		(fp_line
			(start 0.12065 -0.2794)
			(end 0.12065 -0.3048)
			(stroke
				(width 0.1)
				(type default)
			)
			(layer "F.Fab")
		)
		(fp_line
			(start 0.67945 -0.3048)
			(end 0.67945 0.3048)
			(stroke
				(width 0.1)
				(type default)
			)
			(layer "F.Fab")
		)
		(fp_line
			(start 0.67945 0.3048)
			(end 0.120396 0.3048)
			(stroke
				(width 0.1)
				(type default)
			)
			(layer "F.Fab")
		)
		(pad "1" smd rect
			(at -0.40005 0 180)
			(size 0.4572 0.508)
			(layers "F.Cu" "F.Mask" "F.Paste")
			(net "FAN_1_FAIL_LED_R_N")
		)
		(pad "2" smd rect
			(at 0.40005 0 180)
			(size 0.4572 0.508)
			(layers "F.Cu" "F.Mask" "F.Paste")
			(net "FAN_1_FAIL_R_LED_N")
		)
	)
	(footprint ""
		(layer "F.Cu")
		(at 16.393922 -194.250056)
		(property "Reference" "C2044"
			(at 0 0 0)
			(layer "F.SilkS")
			(hide yes)
			(effects
				(font
					(size 1.27 1.27)
				)
			)
		)
		(property "Value" ""
			(at 0 0 0)
			(layer "F.Fab")
			(effects
				(font
					(size 1.27 1.27)
				)
			)
		)
		(duplicate_pad_numbers_are_jumpers no)
		(fp_line
			(start -0.7874 -0.4064)
			(end 0.7874 -0.4064)
			(stroke
				(width 0.1524)
				(type default)
			)
			(layer "F.SilkS")
		)
		(fp_line
			(start -0.7874 0.4064)
			(end -0.7874 -0.4064)
			(stroke
				(width 0.1524)
				(type default)
			)
			(layer "F.SilkS")
		)
		(fp_line
			(start 0.7874 -0.4064)
			(end 0.7874 0.4064)
			(stroke
				(width 0.1524)
				(type default)
			)
			(layer "F.SilkS")
		)
		(fp_line
			(start 0.7874 0.4064)
			(end -0.7874 0.4064)
			(stroke
				(width 0.1524)
				(type default)
			)
			(layer "F.SilkS")
		)
		(fp_line
			(start -0.67945 -0.305054)
			(end -0.12065 -0.305054)
			(stroke
				(width 0.1)
				(type default)
			)
			(layer "F.Fab")
		)
		(fp_line
			(start -0.67945 0.3048)
			(end -0.67945 -0.305054)
			(stroke
				(width 0.1)
				(type default)
			)
			(layer "F.Fab")
		)
		(fp_line
			(start -0.12065 -0.305054)
			(end -0.12065 -0.2794)
			(stroke
				(width 0.1)
				(type default)
			)
			(layer "F.Fab")
		)
		(fp_line
			(start -0.12065 -0.2794)
			(end 0.12065 -0.2794)
			(stroke
				(width 0.1)
				(type default)
			)
			(layer "F.Fab")
		)
		(fp_line
			(start -0.12065 0.2794)
			(end -0.12065 0.3048)
			(stroke
				(width 0.1)
				(type default)
			)
			(layer "F.Fab")
		)
		(fp_line
			(start -0.12065 0.3048)
			(end -0.67945 0.3048)
			(stroke
				(width 0.1)
				(type default)
			)
			(layer "F.Fab")
		)
		(fp_line
			(start 0.120396 0.2794)
			(end -0.12065 0.2794)
			(stroke
				(width 0.1)
				(type default)
			)
			(layer "F.Fab")
		)
		(fp_line
			(start 0.120396 0.3048)
			(end 0.120396 0.2794)
			(stroke
				(width 0.1)
				(type default)
			)
			(layer "F.Fab")
		)
		(fp_line
			(start 0.12065 -0.3048)
			(end 0.67945 -0.3048)
			(stroke
				(width 0.1)
				(type default)
			)
			(layer "F.Fab")
		)
		(fp_line
			(start 0.12065 -0.2794)
			(end 0.12065 -0.3048)
			(stroke
				(width 0.1)
				(type default)
			)
			(layer "F.Fab")
		)
		(fp_line
			(start 0.67945 -0.3048)
			(end 0.67945 0.3048)
			(stroke
				(width 0.1)
				(type default)
			)
			(layer "F.Fab")
		)
		(fp_line
			(start 0.67945 0.3048)
			(end 0.120396 0.3048)
			(stroke
				(width 0.1)
				(type default)
			)
			(layer "F.Fab")
		)
		(pad "1" smd circle
			(at -0.40005 0)
			(size 0 0)
			(layers "F.Cu" "F.Mask" "F.Paste")
			(net "FAN_6_PWM_OL_R")
		)
		(pad "2" smd circle
			(at 0.40005 0)
			(size 0 0)
			(layers "F.Cu" "F.Mask" "F.Paste")
			(net "GND")
		)
	)
	(footprint ""
		(layer "F.Cu")
		(at 24.257 -98.552)
		(property "Reference" ""
			(at 0 0 0)
			(layer "F.SilkS")
			(hide yes)
			(effects
				(font
					(size 1.27 1.27)
				)
			)
		)
		(property "Value" ""
			(at 0 0 0)
			(layer "F.Fab")
			(effects
				(font
					(size 1.27 1.27)
				)
			)
		)
		(duplicate_pad_numbers_are_jumpers no)
		(pad "1" smd circle
			(at 0 0)
			(size 0.9906 0.9906)
			(layers "F.Cu" "F.Mask" "F.Paste")
			(net "Net_127")
		)
		(zone
			(layer "F.Cu")
			(hatch none 0.5)
			(connect_pads
				(clearance 0)
			)
			(min_thickness 0.25)
			(keepout
				(tracks not_allowed)
				(vias allowed)
				(pads allowed)
				(copperpour not_allowed)
				(footprints allowed)
			)
			(placement
				(enabled no)
				(sheetname "")
			)
			(fill
				(thermal_gap 0.5)
				(thermal_bridge_width 0.5)
				(island_removal_mode 0)
			)
			(polygon
				(pts
					(arc
						(start 25.8826 -98.552)
						(mid 22.6314 -98.552)
						(end 25.8826 -98.552)
					)
				)
			)
		)
	)
	(footprint ""
		(layer "F.Cu")
		(at 42.037 -186.182 180)
		(property "Reference" "R4958"
			(at 0 0 180)
			(layer "F.SilkS")
			(hide yes)
			(effects
				(font
					(size 1.27 1.27)
				)
			)
		)
		(property "Value" ""
			(at 0 0 180)
			(layer "F.Fab")
			(effects
				(font
					(size 1.27 1.27)
				)
			)
		)
		(duplicate_pad_numbers_are_jumpers no)
		(fp_line
			(start 0.7874 0.4064)
			(end -0.7874 0.4064)
			(stroke
				(width 0.1524)
				(type default)
			)
			(layer "F.SilkS")
		)
		(fp_line
			(start 0.7874 -0.4064)
			(end 0.7874 0.4064)
			(stroke
				(width 0.1524)
				(type default)
			)
			(layer "F.SilkS")
		)
		(fp_line
			(start -0.7874 0.4064)
			(end -0.7874 -0.4064)
			(stroke
				(width 0.1524)
				(type default)
			)
			(layer "F.SilkS")
		)
		(fp_line
			(start -0.7874 -0.4064)
			(end 0.7874 -0.4064)
			(stroke
				(width 0.1524)
				(type default)
			)
			(layer "F.SilkS")
		)
		(fp_line
			(start 0.67945 0.3048)
			(end 0.120396 0.3048)
			(stroke
				(width 0.1)
				(type default)
			)
			(layer "F.Fab")
		)
		(fp_line
			(start 0.67945 -0.3048)
			(end 0.67945 0.3048)
			(stroke
				(width 0.1)
				(type default)
			)
			(layer "F.Fab")
		)
		(fp_line
			(start 0.12065 -0.2794)
			(end 0.12065 -0.3048)
			(stroke
				(width 0.1)
				(type default)
			)
			(layer "F.Fab")
		)
		(fp_line
			(start 0.12065 -0.3048)
			(end 0.67945 -0.3048)
			(stroke
				(width 0.1)
				(type default)
			)
			(layer "F.Fab")
		)
		(fp_line
			(start 0.120396 0.3048)
			(end 0.120396 0.2794)
			(stroke
				(width 0.1)
				(type default)
			)
			(layer "F.Fab")
		)
		(fp_line
			(start 0.120396 0.2794)
			(end -0.12065 0.2794)
			(stroke
				(width 0.1)
				(type default)
			)
			(layer "F.Fab")
		)
		(fp_line
			(start -0.12065 0.3048)
			(end -0.67945 0.3048)
			(stroke
				(width 0.1)
				(type default)
			)
			(layer "F.Fab")
		)
		(fp_line
			(start -0.12065 0.2794)
			(end -0.12065 0.3048)
			(stroke
				(width 0.1)
				(type default)
			)
			(layer "F.Fab")
		)
		(fp_line
			(start -0.12065 -0.2794)
			(end 0.12065 -0.2794)
			(stroke
				(width 0.1)
				(type default)
			)
			(layer "F.Fab")
		)
		(fp_line
			(start -0.12065 -0.305054)
			(end -0.12065 -0.2794)
			(stroke
				(width 0.1)
				(type default)
			)
			(layer "F.Fab")
		)
		(fp_line
			(start -0.67945 0.3048)
			(end -0.67945 -0.305054)
			(stroke
				(width 0.1)
				(type default)
			)
			(layer "F.Fab")
		)
		(fp_line
			(start -0.67945 -0.305054)
			(end -0.12065 -0.305054)
			(stroke
				(width 0.1)
				(type default)
			)
			(layer "F.Fab")
		)
		(pad "1" smd circle
			(at -0.40005 0 180)
			(size 0 0)
			(layers "F.Cu" "F.Mask" "F.Paste")
			(net "P3V3_AUX")
		)
		(pad "2" smd circle
			(at 0.40005 0 180)
			(size 0 0)
			(layers "F.Cu" "F.Mask" "F.Paste")
			(net "P52V_FAN_7_BUFF_EN")
		)
	)
	(footprint ""
		(layer "F.Cu")
		(at 15.113 -26.924 -90)
		(property "Reference" "R5349"
			(at 0 0 270)
			(layer "F.SilkS")
			(hide yes)
			(effects
				(font
					(size 1.27 1.27)
				)
			)
		)
		(property "Value" ""
			(at 0 0 270)
			(layer "F.Fab")
			(effects
				(font
					(size 1.27 1.27)
				)
			)
		)
		(duplicate_pad_numbers_are_jumpers no)
		(fp_line
			(start -0.7874 0.4064)
			(end -0.7874 -0.4064)
			(stroke
				(width 0.1524)
				(type default)
			)
			(layer "F.SilkS")
		)
		(fp_line
			(start 0.7874 0.4064)
			(end -0.7874 0.4064)
			(stroke
				(width 0.1524)
				(type default)
			)
			(layer "F.SilkS")
		)
		(fp_line
			(start -0.7874 -0.4064)
			(end 0.7874 -0.4064)
			(stroke
				(width 0.1524)
				(type default)
			)
			(layer "F.SilkS")
		)
		(fp_line
			(start 0.7874 -0.4064)
			(end 0.7874 0.4064)
			(stroke
				(width 0.1524)
				(type default)
			)
			(layer "F.SilkS")
		)
		(fp_line
			(start -0.67945 0.3048)
			(end -0.67945 -0.305054)
			(stroke
				(width 0.1)
				(type default)
			)
			(layer "F.Fab")
		)
		(fp_line
			(start -0.12065 0.3048)
			(end -0.67945 0.3048)
			(stroke
				(width 0.1)
				(type default)
			)
			(layer "F.Fab")
		)
		(fp_line
			(start 0.120396 0.3048)
			(end 0.120396 0.2794)
			(stroke
				(width 0.1)
				(type default)
			)
			(layer "F.Fab")
		)
		(fp_line
			(start 0.67945 0.3048)
			(end 0.120396 0.3048)
			(stroke
				(width 0.1)
				(type default)
			)
			(layer "F.Fab")
		)
		(fp_line
			(start -0.12065 0.2794)
			(end -0.12065 0.3048)
			(stroke
				(width 0.1)
				(type default)
			)
			(layer "F.Fab")
		)
		(fp_line
			(start 0.120396 0.2794)
			(end -0.12065 0.2794)
			(stroke
				(width 0.1)
				(type default)
			)
			(layer "F.Fab")
		)
		(fp_line
			(start -0.12065 -0.2794)
			(end 0.12065 -0.2794)
			(stroke
				(width 0.1)
				(type default)
			)
			(layer "F.Fab")
		)
		(fp_line
			(start 0.12065 -0.2794)
			(end 0.12065 -0.3048)
			(stroke
				(width 0.1)
				(type default)
			)
			(layer "F.Fab")
		)
		(fp_line
			(start 0.12065 -0.3048)
			(end 0.67945 -0.3048)
			(stroke
				(width 0.1)
				(type default)
			)
			(layer "F.Fab")
		)
		(fp_line
			(start 0.67945 -0.3048)
			(end 0.67945 0.3048)
			(stroke
				(width 0.1)
				(type default)
			)
			(layer "F.Fab")
		)
		(fp_line
			(start -0.67945 -0.305054)
			(end -0.12065 -0.305054)
			(stroke
				(width 0.1)
				(type default)
			)
			(layer "F.Fab")
		)
		(fp_line
			(start -0.12065 -0.305054)
			(end -0.12065 -0.2794)
			(stroke
				(width 0.1)
				(type default)
			)
			(layer "F.Fab")
		)
		(pad "1" smd rect
			(at -0.40005 0 90)
			(size 0.4572 0.508)
			(layers "F.Cu" "F.Mask" "F.Paste")
			(net "FAN_4_OK_LED_R_N")
		)
		(pad "2" smd rect
			(at 0.40005 0 90)
			(size 0.4572 0.508)
			(layers "F.Cu" "F.Mask" "F.Paste")
			(net "FAN_4_OK_R_LED_N")
		)
	)
	(footprint ""
		(layer "F.Cu")
		(at 33.528 -31.623)
		(property "Reference" "D285"
			(at 1.397 -1.62433 0)
			(unlocked yes)
			(layer "F.SilkS")
			(effects
				(font
					(size 0.7874 0.5842)
					(thickness 0.1524)
				)
				(justify left)
			)
		)
		(property "Value" ""
			(at 0 0 0)
			(layer "F.Fab")
			(effects
				(font
					(size 1.27 1.27)
				)
			)
		)
		(duplicate_pad_numbers_are_jumpers no)
		(fp_line
			(start -0.854964 -0.450088)
			(end -0.854964 0.450088)
			(stroke
				(width 0.1524)
				(type default)
			)
			(layer "F.SilkS")
		)
		(fp_line
			(start -0.854964 0.450088)
			(end 0.925068 0.450088)
			(stroke
				(width 0.1524)
				(type default)
			)
			(layer "F.SilkS")
		)
		(fp_line
			(start 0.845058 0.4064)
			(end 0.845058 -0.381)
			(stroke
				(width 0.1524)
				(type default)
			)
			(layer "F.SilkS")
		)
		(fp_line
			(start 0.870458 -0.2794)
			(end 0.845058 0.4064)
			(stroke
				(width 0.1524)
				(type default)
			)
			(layer "F.SilkS")
		)
		(fp_line
			(start 0.94488 -0.450088)
			(end -0.854964 -0.450088)
			(stroke
				(width 0.1524)
				(type default)
			)
			(layer "F.SilkS")
		)
		(fp_line
			(start 0.94488 0.450088)
			(end 0.94488 -0.450088)
			(stroke
				(width 0.1524)
				(type default)
			)
			(layer "F.SilkS")
		)
		(fp_line
			(start -0.54991 -0.350012)
			(end -0.54991 0.350012)
			(stroke
				(width 0.1)
				(type default)
			)
			(layer "F.Fab")
		)
		(fp_line
			(start -0.54991 0.350012)
			(end 0.54991 0.350012)
			(stroke
				(width 0.1)
				(type default)
			)
			(layer "F.Fab")
		)
		(fp_line
			(start 0.54991 -0.350012)
			(end -0.54991 -0.350012)
			(stroke
				(width 0.1)
				(type default)
			)
			(layer "F.Fab")
		)
		(fp_line
			(start 0.54991 0.350012)
			(end 0.54991 -0.350012)
			(stroke
				(width 0.1)
				(type default)
			)
			(layer "F.Fab")
		)
		(fp_text user "+"
			(at -0.7112 -0.00889 180)
			(unlocked yes)
			(layer "F.SilkS")
			(effects
				(font
					(size 1.905 1.4224)
					(thickness 0.1524)
				)
				(justify left)
			)
		)
		(fp_text user "-"
			(at 2.31648 0.39751 180)
			(unlocked yes)
			(layer "F.SilkS")
			(effects
				(font
					(size 1.905 1.4224)
					(thickness 0.1524)
				)
				(justify left)
			)
		)
		(fp_text user "+"
			(at -0.808228 0.239014 180)
			(unlocked yes)
			(layer "F.Fab")
			(effects
				(font
					(size 1.905 1.4224)
					(thickness 0.1524)
				)
				(justify left)
			)
		)
		(fp_text user "-"
			(at 2.48539 0.239014 180)
			(unlocked yes)
			(layer "F.Fab")
			(effects
				(font
					(size 1.905 1.4224)
					(thickness 0.1524)
				)
				(justify left)
			)
		)
		(pad "A" smd rect
			(at -0.424942 0)
			(size 0.5588 0.6096)
			(layers "F.Cu" "F.Mask" "F.Paste")
			(net "GND")
		)
		(pad "C" smd rect
			(at 0.424942 0 180)
			(size 0.5588 0.6096)
			(layers "F.Cu" "F.Mask" "F.Paste")
			(net "FAN_3_PWM_OL_R")
		)
	)
)
